PARTS LIST

78.10521.2BL       C603H36            C1
78.10621.22L       C1206H71           C2
020.F0496.0020     G846A20120T1HR     CN1
083.00195.0B70     LED-1615-4PH26     LED1
083.00195.0B70     LED-1615-4PH26     LED2
083.00195.0B70     LED-1615-4PH26     LED3
083.00195.0B70     LED-1615-4PH26     LED4
083.00195.0B70     LED-1615-4PH26     LED5
083.00195.0B70     LED-1615-4PH26     LED6
84.2N702.J31       SOT23DGS2D4H44     Q1
084.3K324.0031     SOT23DGS2D4H35     Q2
84.2N702.J31       SOT23DGS2D4H44     Q3
084.3K324.0031     SOT23DGS2D4H35     Q4
84.2N702.J31       SOT23DGS2D4H44     Q5
084.3K324.0031     SOT23DGS2D4H35     Q6
84.2N702.J31       SOT23DGS2D4H44     Q7
084.3K324.0031     SOT23DGS2D4H35     Q8
84.2N702.J31       SOT23DGS2D4H44     Q9
084.3K324.0031     SOT23DGS2D4H35     Q10
84.2N702.J31       SOT23DGS2D4H44     Q11
084.3K324.0031     SOT23DGS2D4H35     Q12
64.13005.55L       R603H22            R1
64.91R05.55L       R603H22            R2
64.13005.55L       R603H22            R3
64.91R05.55L       R603H22            R4
64.13005.55L       R603H22            R5
64.91R05.55L       R603H22            R6
64.13005.55L       R603H22            R7
64.91R05.55L       R603H22            R8
64.13005.55L       R603H22            R9
64.91R05.55L       R603H22            R10
64.13005.55L       R603H22            R11
64.91R05.55L       R603H22            R12
64.47015.6DL       R402H16            R13
64.47015.6DL       R402H16            R14
64.47015.6DL       R402H16            R15
64.47015.6DL       R402H16            R16
64.47015.6DL       R402H16            R17
64.47015.6DL       R402H16            R18
64.47015.6DL       R402H16            R19
64.47015.6DL       R402H16            R20
64.47015.6DL       R402H16            R21
64.47015.6DL       R402H16            R22
64.47015.6DL       R402H16            R23
64.47015.6DL       R402H16            R24

EOS

POSITION

C1       1525.00     263.00    270.000    BOT
C2       1515.00     195.00    270.000    BOT
CN1      1935.04     468.50      0.000    BOT
LED1      535.43     590.55      0.000    TOP
LED2     1777.56     590.55      0.000    TOP
LED3     3019.69     590.55      0.000    TOP
LED4     4261.81     590.55      0.000    TOP
LED5     5503.94     590.55      0.000    TOP
LED6     6746.06     590.55      0.000    TOP
Q1        737.00     213.00      0.000    BOT
Q2        878.00     213.00      0.000    BOT
Q3       1120.00     199.00      0.000    BOT
Q4       1261.00     199.00      0.000    BOT
Q5       2692.07     222.54      0.000    BOT
Q6       2551.07     222.54      0.000    BOT
Q7       4189.00     233.00      0.000    BOT
Q8       4331.00     233.00      0.000    BOT
Q9       5451.00     225.00      0.000    BOT
Q10      5593.00     225.00      0.000    BOT
Q11      6375.00     220.00      0.000    BOT
Q12      6517.00     220.00      0.000    BOT
R1        643.00     229.00    180.000    BOT
R2        972.00     234.00    180.000    BOT
R3       1026.00     234.00    180.000    BOT
R4       1355.00     220.00    180.000    BOT
R5       2457.53     244.17    180.000    BOT
R6       2785.74     238.70    180.000    BOT
R7       4094.00     237.00    180.000    BOT
R8       4425.00     237.00    180.000    BOT
R9       5357.00     233.00    180.000    BOT
R10      5688.00     232.00    180.000    BOT
R11      6280.00     226.00    180.000    BOT
R12      6611.00     227.00    180.000    BOT
R13       762.00     114.00    270.000    BOT
R14       901.00     118.00    270.000    BOT
R15      1167.00     104.00    270.000    BOT
R16      1295.00     104.00    270.000    BOT
R17      2702.22     127.86    270.000    BOT
R18      2547.11     127.70    270.000    BOT
R19      4198.00     138.00    270.000    BOT
R20      4339.00     138.00    270.000    BOT
R21      5465.00     130.00    270.000    BOT
R22      5600.00     130.00    270.000    BOT
R23      6383.00     123.00    270.000    BOT
R24      6534.00     125.00    270.000    BOT

EOS

#From(Function(Sicard.Report) Version 3.0)